FILE_TYPE = CONNECTIVITY;
{Allegro Design Entry HDL 17.2-2016 S081 (4005846) 1/11/2022}
"PAGE_NUMBER" = 84;
0"NC";
1"P3V3_AUX\g";
2"P12V_S3_AUX_CPU0_NVDIMM\g";
3"P12V_S3_AUX_CPU0_NVDIMM\g";
4"P3V3_AUX\g";
5"GND\g";
6"GND\g";
7"GND\g";
8"GND\g";
9"GND\g";
10"M_B_CPU0_SA_DQ<31:0>";
11"M_B_CPU0_SA_CB<7:0>";
12"M_B_CPU0_SB_CB<7:0>";
13"M_B_CPU0_SA_CA<6:0>";
14"M_B_CPU0_SB_CA<6:0>";
15"M_B_CPU0_SB_DQ<31:0>";
16"M_B_CPU0_SA_DQS_DP<9:0>";
17"M_B_CPU0_SB_DQS_DP<9:0>";
18"M_B_CPU0_SA_DQS_DN<9:0>";
19"M_B_CPU0_SB_DQS_DN<9:0>";
20"M_B_CPU0_SB_DQ<2>";
21"M_B_CPU0_SB_CB<4>";
22"PD_CHB_CPU0_DIMM1_SAA";
23"I3C_SPD_DDRABCD_CPU0_LVC1_SDA";
24"I3C_SPD_DDRABCD_CPU0_LVC1_SCL_R3";
25"M_B_CPU0_ALERT_N";
26"RST_M_AB_CPU0_FPGA_N";
27"I3C_SPD_DDRABCD_CPU0_LVC1_SCL";
28"M_B_CPU0_SB_CB<2>";
29"M_B_CPU0_SA_DQS_DN<3>";
30"M_B_CPU0_SA_DQS_DN<4>";
31"M_B_CPU0_SA_DQS_DN<5>";
32"M_B_CPU0_SB_DQS_DN<3>";
33"M_B_CPU0_SB_DQS_DN<2>";
34"M_B_CPU0_SB_DQS_DP<1>";
35"M_B_CPU0_SB_DQS_DP<9>";
36"M_B_CPU0_SA_DQS_DN<0>";
37"M_B_CPU0_SB_DQS_DN<1>";
38"M_B_CPU0_SB_DQS_DN<0>";
39"M_B_CPU0_SB_DQS_DN<4>";
40"M_B_CPU0_SB_DQS_DN<5>";
41"M_B_CPU0_SB_DQS_DN<6>";
42"M_B_CPU0_SB_DQS_DN<7>";
43"M_B_CPU0_SB_DQS_DN<8>";
44"M_B_CPU0_SB_DQS_DN<9>";
45"M_B_CPU0_SA_DQS_DN<1>";
46"M_B_CPU0_SA_DQS_DN<2>";
47"M_B_CPU0_SA_DQS_DN<6>";
48"M_B_CPU0_SA_DQS_DN<7>";
49"M_B_CPU0_SA_DQS_DN<8>";
50"M_B_CPU0_SA_DQS_DN<9>";
51"M_B_CPU0_SB_DQS_DP<0>";
52"M_B_CPU0_SB_DQS_DP<2>";
53"M_B_CPU0_SB_DQS_DP<3>";
54"M_B_CPU0_SB_DQS_DP<4>";
55"M_B_CPU0_SB_DQS_DP<5>";
56"M_B_CPU0_SB_DQS_DP<6>";
57"M_B_CPU0_SB_DQS_DP<7>";
58"M_B_CPU0_SB_DQS_DP<8>";
59"M_B_CPU0_SA_DQS_DP<0>";
60"M_B_CPU0_SA_DQS_DP<1>";
61"M_B_CPU0_SA_DQS_DP<2>";
62"M_B_CPU0_SA_DQS_DP<3>";
63"M_B_CPU0_SA_DQS_DP<4>";
64"M_B_CPU0_SA_DQS_DP<5>";
65"M_B_CPU0_SA_DQS_DP<6>";
66"M_B_CPU0_SA_DQS_DP<7>";
67"M_B_CPU0_SA_DQS_DP<8>";
68"M_B_CPU0_SA_DQS_DP<9>";
69"M_B_CPU0_SB_PAR";
70"M_B_CPU0_SB_CB<0>";
71"M_B_CPU0_SB_CB<6>";
72"M_B_CPU0_SA_DQ<0>";
73"M_B_CPU0_SB_CS_N<0>";
74"M_B_CPU0_SA_CS_N<0>";
75"M_B_CPU0_SA_CS_N<1>";
76"M_B_CPU0_SA_DQ<3>";
77"M_B_CPU0_SA_DQ<2>";
78"M_B_CPU0_SA_CB<4>";
79"M_B_CPU0_SB_CB<3>";
80"M_B_CPU0_CLK_DN<0>";
81"M_B_CPU0_CLK_DP<0>";
82"M_B_CPU0_SA_DQ<7>";
83"TP_CHB_CPU0_DIMM1_FRU_0";
84"TP_CHB_CPU0_DIMM1_FRU_1";
85"TP_CHB_CPU0_DIMM1_FRU_2";
86"TP_CHB_CPU0_DIMM1_FRU_3";
87"TP_CHB_CPU0_DIMM1_FRU_4";
88"TP_CHB_CPU0_DIMM1_FRU_5";
89"TP_CHB_CPU0_DIMM1_FRU_6";
90"PWRGD_CHB_CPU0_DIMM1";
91"M_B_CPU0_SA_PAR";
92"M_B_CPU0_SB_RSP<0>";
93"M_B_CPU0_SA_RSP<0>";
94"M_B_CPU0_SB_DQ<0>";
95"M_B_CPU0_SB_DQ<1>";
96"M_B_CPU0_SB_DQ<3>";
97"M_B_CPU0_SB_DQ<4>";
98"M_B_CPU0_SB_DQ<5>";
99"M_B_CPU0_SB_DQ<6>";
100"M_B_CPU0_SB_DQ<7>";
101"M_B_CPU0_SB_DQ<8>";
102"M_B_CPU0_SB_DQ<9>";
103"M_B_CPU0_SB_DQ<10>";
104"M_B_CPU0_SB_DQ<11>";
105"M_B_CPU0_SB_DQ<12>";
106"M_B_CPU0_SB_DQ<13>";
107"M_B_CPU0_SB_DQ<14>";
108"M_B_CPU0_SB_DQ<15>";
109"M_B_CPU0_SB_DQ<16>";
110"M_B_CPU0_SB_DQ<17>";
111"M_B_CPU0_SB_DQ<18>";
112"M_B_CPU0_SB_DQ<19>";
113"M_B_CPU0_SB_DQ<20>";
114"M_B_CPU0_SB_DQ<21>";
115"M_B_CPU0_SB_DQ<22>";
116"M_B_CPU0_SB_DQ<23>";
117"M_B_CPU0_SB_DQ<24>";
118"M_B_CPU0_SB_DQ<25>";
119"M_B_CPU0_SB_DQ<26>";
120"M_B_CPU0_SB_DQ<27>";
121"M_B_CPU0_SB_DQ<28>";
122"M_B_CPU0_SB_DQ<29>";
123"M_B_CPU0_SB_DQ<30>";
124"M_B_CPU0_SB_DQ<31>";
125"M_B_CPU0_SA_DQ<1>";
126"M_B_CPU0_SA_DQ<4>";
127"M_B_CPU0_SA_DQ<5>";
128"M_B_CPU0_SA_DQ<6>";
129"M_B_CPU0_SA_DQ<8>";
130"M_B_CPU0_SA_DQ<9>";
131"M_B_CPU0_SA_DQ<10>";
132"M_B_CPU0_SA_DQ<11>";
133"M_B_CPU0_SA_DQ<12>";
134"M_B_CPU0_SA_DQ<13>";
135"M_B_CPU0_SA_DQ<14>";
136"M_B_CPU0_SA_DQ<15>";
137"M_B_CPU0_SA_DQ<16>";
138"M_B_CPU0_SA_DQ<17>";
139"M_B_CPU0_SA_DQ<18>";
140"M_B_CPU0_SA_DQ<19>";
141"M_B_CPU0_SA_DQ<20>";
142"M_B_CPU0_SA_DQ<21>";
143"M_B_CPU0_SA_DQ<22>";
144"M_B_CPU0_SA_DQ<23>";
145"M_B_CPU0_SA_DQ<24>";
146"M_B_CPU0_SA_DQ<25>";
147"M_B_CPU0_SA_DQ<26>";
148"M_B_CPU0_SA_DQ<27>";
149"M_B_CPU0_SA_DQ<28>";
150"M_B_CPU0_SA_DQ<29>";
151"M_B_CPU0_SA_DQ<30>";
152"M_B_CPU0_SB_CS_N<1>";
153"M_B_CPU0_SB_CB<1>";
154"M_B_CPU0_SB_CB<5>";
155"M_B_CPU0_SA_CB<0>";
156"M_B_CPU0_SA_CB<2>";
157"M_B_CPU0_SA_CB<3>";
158"M_B_CPU0_SA_CB<5>";
159"M_B_CPU0_SA_CB<6>";
160"M_B_CPU0_SB_CA<6>";
161"M_B_CPU0_SA_CA<6>";
162"M_B_CPU0_SB_CA<5>";
163"M_B_CPU0_SA_CA<5>";
164"M_B_CPU0_SB_CA<4>";
165"M_B_CPU0_SA_CA<4>";
166"M_B_CPU0_SB_CA<3>";
167"M_B_CPU0_SA_CA<3>";
168"M_B_CPU0_SB_CA<2>";
169"M_B_CPU0_SA_CA<2>";
170"M_B_CPU0_SB_CA<1>";
171"M_B_CPU0_SA_CA<1>";
172"M_B_CPU0_SB_CA<0>";
173"M_B_CPU0_SA_CA<0>";
174"M_B_CPU0_SB_CB<7>";
175"M_B_CPU0_SA_CB<1>";
176"M_B_CPU0_SA_CB<7>";
177"M_B_CPU0_SA_DQ<31>";
178"PD_CHB_CPU0_DIMM1_SAA";
%"UNIVERSAL_GND"
"1","(-1525,-475)","0","logical_power","I1";
;
CDS_LIB"logical_power"
HDL_POWER"GND";
"A"9;
%"Q_RES"
"2","(-1525,-250)","0","pure_quanta","I10";
;
PART_NUMBER"CS32322FB03"
VALUE"23.2K"
PACK_TYPE"0402LF"
WATTAGE"1/16W"
TOLERANCE"1%"
MATERIAL"CHIP"
$LOCATION"R28"
CDS_LIB"pure_quanta"
CDS_LOCATION"R28"
$SEC"1"
CDS_SEC"1";
"A"
$PN"1"178;
"B"
$PN"2"9;
%"TAP"
"1","(-100,3200)","0","standard","I100";
;
CDS_LIB"standard"
BODY_TYPE"PLUMBING"
HDL_TAP"TRUE";
"B \NAC \NWC"10;
"S \NAC"
BN"17"138;
%"TAP"
"1","(-100,3350)","0","standard","I101";
;
CDS_LIB"standard"
BODY_TYPE"PLUMBING"
HDL_TAP"TRUE";
"B \NAC \NWC"10;
"S \NAC"
BN"20"141;
%"TAP"
"1","(-100,3400)","0","standard","I102";
;
CDS_LIB"standard"
BODY_TYPE"PLUMBING"
HDL_TAP"TRUE";
"B \NAC \NWC"10;
"S \NAC"
BN"21"142;
%"TAP"
"1","(-100,3450)","0","standard","I103";
;
CDS_LIB"standard"
BODY_TYPE"PLUMBING"
HDL_TAP"TRUE";
"B \NAC \NWC"10;
"S \NAC"
BN"22"143;
%"TAP"
"1","(-100,3500)","0","standard","I104";
;
CDS_LIB"standard"
BODY_TYPE"PLUMBING"
HDL_TAP"TRUE";
"B \NAC \NWC"10;
"S \NAC"
BN"23"144;
%"TAP"
"1","(-100,3550)","0","standard","I105";
;
CDS_LIB"standard"
BODY_TYPE"PLUMBING"
HDL_TAP"TRUE";
"B \NAC \NWC"10;
"S \NAC"
BN"24"145;
%"TAP"
"1","(-100,3600)","0","standard","I106";
;
CDS_LIB"standard"
BODY_TYPE"PLUMBING"
HDL_TAP"TRUE";
"B \NAC \NWC"10;
"S \NAC"
BN"25"146;
%"TAP"
"1","(-100,3650)","0","standard","I107";
;
CDS_LIB"standard"
BODY_TYPE"PLUMBING"
HDL_TAP"TRUE";
"B \NAC \NWC"10;
"S \NAC"
BN"26"147;
%"TAP"
"1","(-1750,3700)","2","standard","I109";
;
CDS_LIB"standard"
BODY_TYPE"PLUMBING"
HDL_TAP"TRUE";
"B \NAC \NWC"13;
"S \NAC"
BN"2"169;
%"TAP"
"1","(-1750,3750)","2","standard","I110";
;
CDS_LIB"standard"
BODY_TYPE"PLUMBING"
HDL_TAP"TRUE";
"B \NAC \NWC"13;
"S \NAC"
BN"3"167;
%"TAP"
"1","(-1750,3800)","2","standard","I111";
;
CDS_LIB"standard"
BODY_TYPE"PLUMBING"
HDL_TAP"TRUE";
"B \NAC \NWC"13;
"S \NAC"
BN"4"165;
%"TAP"
"1","(-1750,3900)","2","standard","I112";
;
CDS_LIB"standard"
BODY_TYPE"PLUMBING"
HDL_TAP"TRUE";
"B \NAC \NWC"13;
"S \NAC"
BN"6"161;
%"TAP"
"1","(-1750,3850)","2","standard","I113";
;
CDS_LIB"standard"
BODY_TYPE"PLUMBING"
HDL_TAP"TRUE";
"B \NAC \NWC"13;
"S \NAC"
BN"5"163;
%"TAP"
"1","(-100,3800)","0","standard","I114";
;
CDS_LIB"standard"
BODY_TYPE"PLUMBING"
HDL_TAP"TRUE";
"B \NAC \NWC"10;
"S \NAC"
BN"29"150;
%"TAP"
"1","(-100,3700)","0","standard","I115";
;
CDS_LIB"standard"
BODY_TYPE"PLUMBING"
HDL_TAP"TRUE";
"B \NAC \NWC"10;
"S \NAC"
BN"27"148;
%"TAP"
"1","(-100,3750)","0","standard","I116";
;
CDS_LIB"standard"
BODY_TYPE"PLUMBING"
HDL_TAP"TRUE";
"B \NAC \NWC"10;
"S \NAC"
BN"28"149;
%"TAP"
"1","(-100,3850)","0","standard","I117";
;
CDS_LIB"standard"
BODY_TYPE"PLUMBING"
HDL_TAP"TRUE";
"B \NAC \NWC"10;
"S \NAC"
BN"30"151;
%"TAP"
"1","(-100,3900)","0","standard","I118";
;
CDS_LIB"standard"
BODY_TYPE"PLUMBING"
HDL_TAP"TRUE";
"B \NAC \NWC"10;
"S \NAC"
BN"31"177;
%"VCC_CORE"
"1","(1625,350)","0","logical_power","I119";
;
HDL_POWER"P3V3_AUX"
CDS_LIB"logical_power";
"A"4;
%"UNIVERSAL_GND"
"1","(1625,-350)","0","logical_power","I120";
;
CDS_LIB"logical_power"
HDL_POWER"GND";
"A"8;
%"Q_CAP"
"1","(1625,25)","0","pure_quanta","I121";
;
PART_NUMBER"CH5221MEB00"
VOLTAGE"6.3V"
VALUE"2.2UF"
TOLERANCE"20%"
MATERIAL"X6S"
PACK_TYPE"C0402"
$LOCATION"C8"
CDS_LIB"pure_quanta"
CDS_LOCATION"C8"
$SEC"1"
CDS_SEC"1";
"B"
$PN"2"8;
"A"
$PN"1"4;
%"Q_CAP"
"1","(2625,25)","0","pure_quanta","I122";
;
PART_NUMBER"CH6103KEA00"
VOLTAGE"16V"
TOLERANCE"10%"
PACK_TYPE"C0805"
VALUE"10UF"
MATERIAL"X6S"
$LOCATION"C9"
CDS_LIB"pure_quanta"
CDS_LOCATION"C9"
$SEC"1"
CDS_SEC"1";
"B"
$PN"2"7;
"A"
$PN"1"3;
%"VCC_CORE"
"1","(2625,350)","0","logical_power","I123";
;
HDL_POWER"P12V_S3_AUX_CPU0_NVDIMM"
CDS_LIB"logical_power";
"A"3;
%"TAP"
"1","(2625,1950)","0","standard","I126";
;
CDS_LIB"standard"
BODY_TYPE"PLUMBING"
HDL_TAP"TRUE";
"B \NAC \NWC"17;
"S \NAC"
BN"0"51;
%"TAP"
"1","(2625,2150)","0","standard","I127";
;
CDS_LIB"standard"
BODY_TYPE"PLUMBING"
HDL_TAP"TRUE";
"B \NAC \NWC"17;
"S \NAC"
BN"2"52;
%"TAP"
"1","(2625,2050)","0","standard","I128";
;
CDS_LIB"standard"
BODY_TYPE"PLUMBING"
HDL_TAP"TRUE";
"B \NAC \NWC"17;
"S \NAC"
BN"1"34;
%"TAP"
"1","(2625,2250)","0","standard","I129";
;
CDS_LIB"standard"
BODY_TYPE"PLUMBING"
HDL_TAP"TRUE";
"B \NAC \NWC"17;
"S \NAC"
BN"3"53;
%"VCC_CORE"
"1","(-2575,1775)","0","logical_power","I13";
;
HDL_POWER"P3V3_AUX"
CDS_LIB"logical_power";
"A"1;
%"TAP"
"1","(2625,2350)","0","standard","I130";
;
CDS_LIB"standard"
BODY_TYPE"PLUMBING"
HDL_TAP"TRUE";
"B \NAC \NWC"17;
"S \NAC"
BN"4"54;
%"TAP"
"1","(2625,2450)","0","standard","I131";
;
CDS_LIB"standard"
BODY_TYPE"PLUMBING"
HDL_TAP"TRUE";
"B \NAC \NWC"17;
"S \NAC"
BN"5"55;
%"TAP"
"1","(2625,2650)","0","standard","I132";
;
CDS_LIB"standard"
BODY_TYPE"PLUMBING"
HDL_TAP"TRUE";
"B \NAC \NWC"17;
"S \NAC"
BN"7"57;
%"TAP"
"1","(2625,2550)","0","standard","I133";
;
CDS_LIB"standard"
BODY_TYPE"PLUMBING"
HDL_TAP"TRUE";
"B \NAC \NWC"17;
"S \NAC"
BN"6"56;
%"TAP"
"1","(2625,2750)","0","standard","I134";
;
CDS_LIB"standard"
BODY_TYPE"PLUMBING"
HDL_TAP"TRUE";
"B \NAC \NWC"17;
"S \NAC"
BN"8"58;
%"TAP"
"1","(2625,2850)","0","standard","I135";
;
CDS_LIB"standard"
BODY_TYPE"PLUMBING"
HDL_TAP"TRUE";
"B \NAC \NWC"17;
"S \NAC"
BN"9"35;
%"TAP"
"1","(2625,3000)","0","standard","I136";
;
CDS_LIB"standard"
BODY_TYPE"PLUMBING"
HDL_TAP"TRUE";
"B \NAC \NWC"16;
"S \NAC"
BN"0"59;
%"TAP"
"1","(2625,3100)","0","standard","I137";
;
CDS_LIB"standard"
BODY_TYPE"PLUMBING"
HDL_TAP"TRUE";
"B \NAC \NWC"16;
"S \NAC"
BN"1"60;
%"TAP"
"1","(2625,3200)","0","standard","I138";
;
CDS_LIB"standard"
BODY_TYPE"PLUMBING"
HDL_TAP"TRUE";
"B \NAC \NWC"16;
"S \NAC"
BN"2"61;
%"TAP"
"1","(2625,3300)","0","standard","I139";
;
CDS_LIB"standard"
BODY_TYPE"PLUMBING"
HDL_TAP"TRUE";
"B \NAC \NWC"16;
"S \NAC"
BN"3"62;
%"TAP"
"1","(2625,3400)","0","standard","I140";
;
CDS_LIB"standard"
BODY_TYPE"PLUMBING"
HDL_TAP"TRUE";
"B \NAC \NWC"16;
"S \NAC"
BN"4"63;
%"TAP"
"1","(2625,3500)","0","standard","I141";
;
CDS_LIB"standard"
BODY_TYPE"PLUMBING"
HDL_TAP"TRUE";
"B \NAC \NWC"16;
"S \NAC"
BN"5"64;
%"TAP"
"1","(2625,3600)","0","standard","I142";
;
CDS_LIB"standard"
BODY_TYPE"PLUMBING"
HDL_TAP"TRUE";
"B \NAC \NWC"16;
"S \NAC"
BN"6"65;
%"UNIVERSAL_GND"
"1","(3250,-350)","0","logical_power","I143";
;
CDS_LIB"logical_power"
HDL_POWER"GND";
"A"7;
%"Q_CAP"
"1","(3250,25)","0","pure_quanta","I144";
;
PART_NUMBER"CH6103KEA00"
VALUE"10UF"
VOLTAGE"16V"
TOLERANCE"10%"
PACK_TYPE"C0805"
MATERIAL"X6S"
$LOCATION"C10"
CDS_LIB"pure_quanta"
CDS_LOCATION"C10"
$SEC"1"
CDS_SEC"1";
"B"
$PN"2"7;
"A"
$PN"1"3;
%"UNIVERSAL_GND"
"1","(4325,200)","0","logical_power","I145";
;
CDS_LIB"logical_power"
HDL_POWER"GND";
"A"6;
%"TAP"
"1","(2800,1900)","0","standard","I147";
;
CDS_LIB"standard"
BODY_TYPE"PLUMBING"
HDL_TAP"TRUE";
"B \NAC \NWC"19;
"S \NAC"
BN"0"38;
%"TAP"
"1","(2800,2000)","0","standard","I148";
;
CDS_LIB"standard"
BODY_TYPE"PLUMBING"
HDL_TAP"TRUE";
"B \NAC \NWC"19;
"S \NAC"
BN"1"37;
%"TAP"
"1","(2800,2100)","0","standard","I149";
;
CDS_LIB"standard"
BODY_TYPE"PLUMBING"
HDL_TAP"TRUE";
"B \NAC \NWC"19;
"S \NAC"
BN"2"33;
%"TAP"
"1","(2800,2200)","0","standard","I150";
;
CDS_LIB"standard"
BODY_TYPE"PLUMBING"
HDL_TAP"TRUE";
"B \NAC \NWC"19;
"S \NAC"
BN"3"32;
%"TAP"
"1","(2800,2400)","0","standard","I151";
;
CDS_LIB"standard"
BODY_TYPE"PLUMBING"
HDL_TAP"TRUE";
"B \NAC \NWC"19;
"S \NAC"
BN"5"40;
%"TAP"
"1","(2800,2300)","0","standard","I152";
;
CDS_LIB"standard"
BODY_TYPE"PLUMBING"
HDL_TAP"TRUE";
"B \NAC \NWC"19;
"S \NAC"
BN"4"39;
%"TAP"
"1","(2800,2500)","0","standard","I153";
;
CDS_LIB"standard"
BODY_TYPE"PLUMBING"
HDL_TAP"TRUE";
"B \NAC \NWC"19;
"S \NAC"
BN"6"41;
%"TAP"
"1","(2800,2600)","0","standard","I154";
;
CDS_LIB"standard"
BODY_TYPE"PLUMBING"
HDL_TAP"TRUE";
"B \NAC \NWC"19;
"S \NAC"
BN"7"42;
%"TAP"
"1","(2800,2700)","0","standard","I155";
;
CDS_LIB"standard"
BODY_TYPE"PLUMBING"
HDL_TAP"TRUE";
"B \NAC \NWC"19;
"S \NAC"
BN"8"43;
%"TAP"
"1","(2800,2800)","0","standard","I156";
;
CDS_LIB"standard"
BODY_TYPE"PLUMBING"
HDL_TAP"TRUE";
"B \NAC \NWC"19;
"S \NAC"
BN"9"44;
%"TAP"
"1","(2800,3050)","0","standard","I157";
;
CDS_LIB"standard"
BODY_TYPE"PLUMBING"
HDL_TAP"TRUE";
"B \NAC \NWC"18;
"S \NAC"
BN"1"45;
%"TAP"
"1","(2800,2950)","0","standard","I158";
;
CDS_LIB"standard"
BODY_TYPE"PLUMBING"
HDL_TAP"TRUE";
"B \NAC \NWC"18;
"S \NAC"
BN"0"36;
%"TAP"
"1","(2800,3150)","0","standard","I159";
;
CDS_LIB"standard"
BODY_TYPE"PLUMBING"
HDL_TAP"TRUE";
"B \NAC \NWC"18;
"S \NAC"
BN"2"46;
%"TAP"
"1","(2800,3250)","0","standard","I160";
;
CDS_LIB"standard"
BODY_TYPE"PLUMBING"
HDL_TAP"TRUE";
"B \NAC \NWC"18;
"S \NAC"
BN"3"29;
%"TAP"
"1","(2800,3350)","0","standard","I161";
;
CDS_LIB"standard"
BODY_TYPE"PLUMBING"
HDL_TAP"TRUE";
"B \NAC \NWC"18;
"S \NAC"
BN"4"30;
%"TAP"
"1","(2800,3550)","0","standard","I162";
;
CDS_LIB"standard"
BODY_TYPE"PLUMBING"
HDL_TAP"TRUE";
"B \NAC \NWC"18;
"S \NAC"
BN"6"47;
%"TAP"
"1","(2800,3450)","0","standard","I163";
;
CDS_LIB"standard"
BODY_TYPE"PLUMBING"
HDL_TAP"TRUE";
"B \NAC \NWC"18;
"S \NAC"
BN"5"31;
%"TAP"
"1","(2800,3650)","0","standard","I164";
;
CDS_LIB"standard"
BODY_TYPE"PLUMBING"
HDL_TAP"TRUE";
"B \NAC \NWC"18;
"S \NAC"
BN"7"48;
%"TAP"
"1","(2625,3700)","0","standard","I168";
;
CDS_LIB"standard"
BODY_TYPE"PLUMBING"
HDL_TAP"TRUE";
"B \NAC \NWC"16;
"S \NAC"
BN"7"66;
%"TAP"
"1","(2625,3800)","0","standard","I169";
;
CDS_LIB"standard"
BODY_TYPE"PLUMBING"
HDL_TAP"TRUE";
"B \NAC \NWC"16;
"S \NAC"
BN"8"67;
%"TAP"
"1","(2625,3900)","0","standard","I170";
;
CDS_LIB"standard"
BODY_TYPE"PLUMBING"
HDL_TAP"TRUE";
"B \NAC \NWC"16;
"S \NAC"
BN"9"68;
%"TAP"
"1","(2800,3750)","0","standard","I171";
;
CDS_LIB"standard"
BODY_TYPE"PLUMBING"
HDL_TAP"TRUE";
"B \NAC \NWC"18;
"S \NAC"
BN"8"49;
%"TAP"
"1","(2800,3850)","0","standard","I172";
;
CDS_LIB"standard"
BODY_TYPE"PLUMBING"
HDL_TAP"TRUE";
"B \NAC \NWC"18;
"S \NAC"
BN"9"50;
%"VCC_CORE"
"1","(4325,4450)","0","logical_power","I175";
;
HDL_POWER"P12V_S3_AUX_CPU0_NVDIMM"
CDS_LIB"logical_power";
"A"2;
%"UNIVERSAL_GND"
"1","(6025,200)","0","logical_power","I176";
;
CDS_LIB"logical_power"
HDL_POWER"GND";
"A"5;
%"SCONN288_ADR50017P130CC"
"3","(5175,2275)","0","pure_quanta","I178";
;
PART_NUMBER"DFHST8FS461"
VALUE"SCONN288_ADR50017-P130CC"
MATERIAL"IO"
PART_TYPE"SMLF"
LOCATION"J3"
NEEDS_NO_SIZE"TRUE"
CDS_LMAN_SYM_OUTLINE"-450,1775,450,-1775"
CDS_LIB"pure_quanta"
$SEC"3"
CDS_SEC"3";
"G3"
$PN"G3"5;
"G2"
$PN"G2"5;
"G1"
$PN"G1"5;
"VSS62"
$PN"141"5;
"VSS61"
$PN"139"5;
"VSS60"
$PN"136"5;
"VSS58"
$PN"132"5;
"VSS104"
$PN"240"6;
"VSS102"
$PN"235"6;
"VSS100"
$PN"230"6;
"VIN_BULK2"
$PN"146"2;
"VIN_BULK1"
$PN"145"2;
"VIN_BULK0"
$PN"1"2;
"VSS126"
$PN"288"6;
"VSS125"
$PN"286"6;
"VSS124"
$PN"284"6;
"VSS123"
$PN"281"6;
"VSS122"
$PN"279"6;
"VSS121"
$PN"277"6;
"VSS120"
$PN"275"6;
"VSS119"
$PN"273"6;
"VSS118"
$PN"270"6;
"VSS117"
$PN"268"6;
"VSS116"
$PN"266"6;
"VSS115"
$PN"264"6;
"VSS114"
$PN"262"6;
"VSS113"
$PN"259"6;
"VSS112"
$PN"257"6;
"VSS111"
$PN"255"6;
"VSS110"
$PN"253"6;
"VSS109"
$PN"251"6;
"VSS108"
$PN"248"6;
"VSS107"
$PN"246"6;
"VSS106"
$PN"244"6;
"VSS105"
$PN"242"6;
"VSS103"
$PN"237"6;
"VSS101"
$PN"233"6;
"VSS99"
$PN"228"6;
"VSS98"
$PN"226"6;
"VSS97"
$PN"224"6;
"VSS96"
$PN"222"6;
"VSS95"
$PN"219"6;
"VSS94"
$PN"216"6;
"VSS93"
$PN"214"6;
"VSS92"
$PN"212"6;
"VSS91"
$PN"210"6;
"VSS90"
$PN"208"6;
"VSS89"
$PN"206"6;
"VSS88"
$PN"204"6;
"VSS87"
$PN"202"6;
"VSS86"
$PN"199"6;
"VSS85"
$PN"197"6;
"VSS84"
$PN"195"6;
"VSS83"
$PN"193"6;
"VSS82"
$PN"191"6;
"VSS81"
$PN"188"6;
"VSS80"
$PN"186"6;
"VSS79"
$PN"184"6;
"VSS78"
$PN"182"6;
"VSS77"
$PN"180"6;
"VSS76"
$PN"177"6;
"VSS75"
$PN"175"6;
"VSS74"
$PN"173"6;
"VSS73"
$PN"171"6;
"VSS72"
$PN"169"6;
"VSS71"
$PN"166"6;
"VSS70"
$PN"164"6;
"VSS69"
$PN"162"6;
"VSS68"
$PN"160"6;
"VSS67"
$PN"158"6;
"VSS66"
$PN"155"6;
"VSS65"
$PN"153"6;
"VSS64"
$PN"151"6;
"VSS63"
$PN"143"5;
"VSS59"
$PN"134"5;
"VSS57"
$PN"130"5;
"VSS56"
$PN"128"5;
"VSS55"
$PN"125"5;
"VSS54"
$PN"123"5;
"VSS53"
$PN"121"5;
"VSS52"
$PN"119"5;
"VSS51"
$PN"117"5;
"VSS50"
$PN"114"5;
"VSS49"
$PN"112"5;
"VSS48"
$PN"110"5;
"VSS47"
$PN"108"5;
"VSS46"
$PN"106"5;
"VSS45"
$PN"103"5;
"VSS44"
$PN"101"5;
"VSS43"
$PN"99"5;
"VSS42"
$PN"97"5;
"VSS41"
$PN"95"5;
"VSS40"
$PN"92"5;
"VSS39"
$PN"90"5;
"VSS38"
$PN"88"5;
"VSS37"
$PN"85"5;
"VSS36"
$PN"83"5;
"VSS35"
$PN"81"5;
"VSS34"
$PN"79"5;
"VSS33"
$PN"77"5;
"VSS32"
$PN"75"5;
"VSS31"
$PN"73"5;
"VSS30"
$PN"71"5;
"VSS29"
$PN"69"5;
"VSS28"
$PN"67"5;
"VSS27"
$PN"65"5;
"VSS26"
$PN"63"5;
"VSS25"
$PN"61"5;
"VSS24"
$PN"59"5;
"VSS23"
$PN"57"5;
"VSS22"
$PN"54"5;
"VSS21"
$PN"52"5;
"VSS20"
$PN"50"5;
"VSS19"
$PN"48"5;
"VSS18"
$PN"46"5;
"VSS17"
$PN"43"5;
"VSS16"
$PN"41"5;
"VSS15"
$PN"39"5;
"VSS14"
$PN"37"5;
"VSS13"
$PN"35"5;
"VSS12"
$PN"32"5;
"VSS11"
$PN"30"5;
"VSS10"
$PN"28"5;
"VSS9"
$PN"26"5;
"VSS8"
$PN"24"5;
"VSS7"
$PN"21"5;
"VSS6"
$PN"19"5;
"VSS5"
$PN"17"5;
"VSS4"
$PN"15"5;
"VSS3"
$PN"13"5;
"VSS2"
$PN"10"5;
"VSS1"
$PN"8"5;
"VSS0"
$PN"6"5;
%"SCONN288_ADR50017P130CC"
"2","(1725,2900)","0","pure_quanta","I179";
;
PART_NUMBER"DFHST8FS461"
VALUE"SCONN288_ADR50017-P130CC"
MATERIAL"IO"
PART_TYPE"SMLF"
LOCATION"J3"
NEEDS_NO_SIZE"TRUE"
CDS_LMAN_SYM_OUTLINE"-600,1150,600,-1150"
CDS_LIB"pure_quanta"
$SEC"2"
CDS_SEC"2";
"DQS7_A_C||TDQS7_A_C \B"
$PN"178"48;
"DQS6_A_T||TDQS6_A_T"
$PN"168"65;
"DQS8_B_T||TDQS8_B_T"
$PN"283"58;
"DQS8_B_C||TDQS8_B_C \B"
$PN"282"43;
"DQS7_B_T||TDQS7_B_T"
$PN"272"57;
"DQS0_A_C \B"
$PN"12"36;
"DQS0_A_T"
$PN"11"59;
"DQS0_B_C \B"
$PN"105"38;
"DQS0_B_T"
$PN"104"51;
"DQS1_A_C \B"
$PN"23"45;
"DQS1_A_T"
$PN"22"60;
"DQS1_B_C \B"
$PN"116"37;
"DQS1_B_T"
$PN"115"34;
"DQS2_A_C \B"
$PN"34"46;
"DQS2_A_T"
$PN"33"61;
"DQS2_B_C \B"
$PN"127"33;
"DQS2_B_T"
$PN"126"52;
"DQS3_A_C \B"
$PN"45"29;
"DQS3_A_T"
$PN"44"62;
"DQS3_B_C \B"
$PN"138"32;
"DQS3_B_T"
$PN"137"53;
"DQS4_A_C \B"
$PN"56"30;
"DQS4_A_T"
$PN"55"63;
"DQS4_B_C \B"
$PN"238"39;
"DQS4_B_T"
$PN"239"54;
"DQS5_A_C||TDQS5_A_C||DQS5_A_T||TDQS5_A_T \B"
$PN"156"31;
"DQS5_A_T||TDQS5_A_T"
$PN"157"64;
"DQS5_B_C||TDQS5_B_C \B"
$PN"249"40;
"DQS5_B_T||TDQS5_B_T"
$PN"250"55;
"DQS6_A_C||TDQS6_A_C||DQS6_A_T||TDQS6_A_T \B"
$PN"167"47;
"DQS6_B_C||TDQS6_B_C \B"
$PN"260"41;
"DQS6_B_T||TDQS6_B_T"
$PN"261"56;
"DQS7_A_T||TDQS7_A_T"
$PN"179"66;
"DQS7_B_C||TDQS7_B_C \B"
$PN"271"42;
"DQS8_A_C||TDQS8_A_C \B"
$PN"189"49;
"DQS8_A_T||TDQS8_A_T"
$PN"190"67;
"DQS9_A_C||TDQS9_A_C \B"
$PN"200"50;
"DQS9_A_T||TDQS9_A_T"
$PN"201"68;
"DQS9_B_C||TDQS9_B_C \B"
$PN"94"44;
"DQS9_B_T||TDQS9_B_T||DBI4_B_N"
$PN"93"35;
%"SCONN288_ADR50017P130CC"
"1","(-925,2175)","0","pure_quanta","I180";
;
PART_NUMBER"DFHST8FS461"
VALUE"SCONN288_ADR50017-P130CC"
MATERIAL"IO"
PART_TYPE"SMLF"
LOCATION"J3"
NEEDS_NO_SIZE"TRUE"
CDS_LMAN_SYM_OUTLINE"-450,1875,450,-1875"
CDS_LIB"pure_quanta"
$SEC"1"
CDS_SEC"1";
"DQ31_A"
$PN"194"177;
"CB7_A"
$PN"205"176;
"CB4_A"
$PN"58"78;
"CB1_A"
$PN"53"175;
"CB7_B"
$PN"236"174;
"ALERT_N \B"
$PN"62"25;
"CA0_A"
$PN"66"173;
"CA0_B"
$PN"76"172;
"CA1_A"
$PN"211"171;
"CA1_B"
$PN"221"170;
"CA2_A"
$PN"68"169;
"CA2_B"
$PN"78"168;
"CA3_A"
$PN"213"167;
"CA3_B"
$PN"223"166;
"CA4_A"
$PN"70"165;
"CA4_B"
$PN"80"164;
"CA5_A"
$PN"215"163;
"CA5_B"
$PN"225"162;
"CA6_A"
$PN"72"161;
"CA6_B"
$PN"82"160;
"CB6_A"
$PN"203"159;
"CB5_A"
$PN"60"158;
"CB3_A"
$PN"198"157;
"CB2_A"
$PN"196"156;
"CB0_A"
$PN"51"155;
"CB6_B"
$PN"234"71;
"CB5_B"
$PN"91"154;
"CB4_B"
$PN"89"21;
"CB3_B"
$PN"243"79;
"CB2_B"
$PN"241"28;
"CB1_B"
$PN"98"153;
"CB0_B"
$PN"96"70;
"CK_C \B"
$PN"218"80;
"CK_T"
$PN"217"81;
"CS0_A_N"
$PN"64"74;
"CS0_B_N"
$PN"84"73;
"CS1_A_N"
$PN"209"75;
"CS1_B_N"
$PN"229"152;
"DQ30_A"
$PN"192"151;
"DQ29_A"
$PN"49"150;
"DQ28_A"
$PN"47"149;
"DQ27_A"
$PN"187"148;
"DQ26_A"
$PN"185"147;
"DQ25_A"
$PN"42"146;
"DQ24_A"
$PN"40"145;
"DQ23_A"
$PN"183"144;
"DQ22_A"
$PN"181"143;
"DQ21_A"
$PN"38"142;
"DQ20_A"
$PN"36"141;
"DQ19_A"
$PN"176"140;
"DQ18_A"
$PN"174"139;
"DQ17_A"
$PN"31"138;
"DQ16_A"
$PN"29"137;
"DQ15_A"
$PN"172"136;
"DQ14_A"
$PN"170"135;
"DQ13_A"
$PN"27"134;
"DQ12_A"
$PN"25"133;
"DQ11_A"
$PN"165"132;
"DQ10_A"
$PN"163"131;
"DQ9_A"
$PN"20"130;
"DQ8_A"
$PN"18"129;
"DQ7_A"
$PN"161"82;
"DQ6_A"
$PN"159"128;
"DQ5_A"
$PN"16"127;
"DQ4_A"
$PN"14"126;
"DQ3_A"
$PN"154"76;
"DQ2_A"
$PN"152"77;
"DQ1_A"
$PN"9"125;
"DQ0_A"
$PN"7"72;
"DQ31_B"
$PN"287"124;
"DQ30_B"
$PN"285"123;
"DQ29_B"
$PN"142"122;
"DQ28_B"
$PN"140"121;
"DQ27_B"
$PN"280"120;
"DQ26_B"
$PN"278"119;
"DQ25_B"
$PN"135"118;
"DQ24_B"
$PN"133"117;
"DQ23_B"
$PN"276"116;
"DQ22_B"
$PN"274"115;
"DQ21_B"
$PN"131"114;
"DQ20_B"
$PN"129"113;
"DQ19_B"
$PN"269"112;
"DQ18_B"
$PN"267"111;
"DQ17_B"
$PN"124"110;
"DQ16_B"
$PN"122"109;
"DQ15_B"
$PN"265"108;
"DQ14_B"
$PN"263"107;
"DQ13_B"
$PN"120"106;
"DQ12_B"
$PN"118"105;
"DQ11_B"
$PN"258"104;
"DQ10_B"
$PN"256"103;
"DQ9_B"
$PN"113"102;
"DQ8_B"
$PN"111"101;
"DQ7_B"
$PN"254"100;
"DQ6_B"
$PN"252"99;
"DQ5_B"
$PN"109"98;
"DQ4_B"
$PN"107"97;
"DQ3_B"
$PN"247"96;
"DQ2_B"
$PN"245"20;
"DQ1_B"
$PN"102"95;
"DQ0_B"
$PN"100"94;
"HSA"
$PN"148"22;
"HSCL"
$PN"4"24;
"HSDA"
$PN"5"23;
"LBD||RSP_A_N"
$PN"86"93;
"LBS||RSP_B_N"
$PN"87"92;
"PAR_A"
$PN"74"91;
"PAR_B"
$PN"227"69;
"PWR_GOOD||FAIL_N"
$PN"147"90;
"RESET_N \B"
$PN"207"26;
"RFU6"
$PN"232"89;
"RFU5"
$PN"231"88;
"RFU4"
$PN"220"87;
"RFU3"
$PN"150"86;
"RFU2"
$PN"149"85;
"RFU1"
$PN"144"84;
"RFU0"
$PN"2"83;
"VIN_MGMT"
$PN"3"1;
%"Q_RES"
"1","(-2800,1200)","0","pure_quanta","I182";
;
PART_NUMBER"CS04992FB07"
VALUE"49.9"
MATERIAL"CHIP"
$LOCATION"R3877"
CDS_LIB"pure_quanta"
PACK_TYPE"0402LF"
TOLERANCE"1%"
WATTAGE"1/16W"
CDS_LOCATION"R3877"
$SEC"1"
CDS_SEC"1";
"B"
$PN"2"27;
"A"
$PN"1"24;
%"TAP"
"1","(-1750,1750)","2","standard","I24";
;
CDS_LIB"standard"
BODY_TYPE"PLUMBING"
HDL_TAP"TRUE";
"B \NAC \NWC"12;
"S \NAC"
BN"1"153;
%"TAP"
"1","(-1750,1700)","2","standard","I25";
;
CDS_LIB"standard"
BODY_TYPE"PLUMBING"
HDL_TAP"TRUE";
"B \NAC \NWC"12;
"S \NAC"
BN"0"70;
%"TAP"
"1","(-1750,1800)","2","standard","I26";
;
CDS_LIB"standard"
BODY_TYPE"PLUMBING"
HDL_TAP"TRUE";
"B \NAC \NWC"12;
"S \NAC"
BN"2"28;
%"TAP"
"1","(-1750,1850)","2","standard","I27";
;
CDS_LIB"standard"
BODY_TYPE"PLUMBING"
HDL_TAP"TRUE";
"B \NAC \NWC"12;
"S \NAC"
BN"3"79;
%"TAP"
"1","(-1750,1900)","2","standard","I28";
;
CDS_LIB"standard"
BODY_TYPE"PLUMBING"
HDL_TAP"TRUE";
"B \NAC \NWC"12;
"S \NAC"
BN"4"21;
%"TAP"
"1","(-1750,2000)","2","standard","I29";
;
CDS_LIB"standard"
BODY_TYPE"PLUMBING"
HDL_TAP"TRUE";
"B \NAC \NWC"12;
"S \NAC"
BN"6"71;
%"TAP"
"1","(-1750,1950)","2","standard","I30";
;
CDS_LIB"standard"
BODY_TYPE"PLUMBING"
HDL_TAP"TRUE";
"B \NAC \NWC"12;
"S \NAC"
BN"5"154;
%"TAP"
"1","(-1750,2050)","2","standard","I31";
;
CDS_LIB"standard"
BODY_TYPE"PLUMBING"
HDL_TAP"TRUE";
"B \NAC \NWC"12;
"S \NAC"
BN"7"174;
%"TAP"
"1","(-1750,2150)","2","standard","I32";
;
CDS_LIB"standard"
BODY_TYPE"PLUMBING"
HDL_TAP"TRUE";
"B \NAC \NWC"11;
"S \NAC"
BN"0"155;
%"TAP"
"1","(-1750,2200)","2","standard","I33";
;
CDS_LIB"standard"
BODY_TYPE"PLUMBING"
HDL_TAP"TRUE";
"B \NAC \NWC"11;
"S \NAC"
BN"1"175;
%"TAP"
"1","(-1750,2250)","2","standard","I34";
;
CDS_LIB"standard"
BODY_TYPE"PLUMBING"
HDL_TAP"TRUE";
"B \NAC \NWC"11;
"S \NAC"
BN"2"156;
%"TAP"
"1","(-1750,2300)","2","standard","I35";
;
CDS_LIB"standard"
BODY_TYPE"PLUMBING"
HDL_TAP"TRUE";
"B \NAC \NWC"11;
"S \NAC"
BN"3"157;
%"TAP"
"1","(-1750,2350)","2","standard","I36";
;
CDS_LIB"standard"
BODY_TYPE"PLUMBING"
HDL_TAP"TRUE";
"B \NAC \NWC"11;
"S \NAC"
BN"4"78;
%"TAP"
"1","(-1750,2400)","2","standard","I37";
;
CDS_LIB"standard"
BODY_TYPE"PLUMBING"
HDL_TAP"TRUE";
"B \NAC \NWC"11;
"S \NAC"
BN"5"158;
%"TAP"
"1","(-1750,2500)","2","standard","I38";
;
CDS_LIB"standard"
BODY_TYPE"PLUMBING"
HDL_TAP"TRUE";
"B \NAC \NWC"11;
"S \NAC"
BN"7"176;
%"TAP"
"1","(-1750,2450)","2","standard","I39";
;
CDS_LIB"standard"
BODY_TYPE"PLUMBING"
HDL_TAP"TRUE";
"B \NAC \NWC"11;
"S \NAC"
BN"6"159;
%"TAP"
"1","(-1750,3300)","2","standard","I40";
;
CDS_LIB"standard"
BODY_TYPE"PLUMBING"
HDL_TAP"TRUE";
"B \NAC \NWC"14;
"S \NAC"
BN"2"168;
%"TAP"
"1","(-1750,3250)","2","standard","I41";
;
CDS_LIB"standard"
BODY_TYPE"PLUMBING"
HDL_TAP"TRUE";
"B \NAC \NWC"14;
"S \NAC"
BN"1"170;
%"TAP"
"1","(-1750,3200)","2","standard","I42";
;
CDS_LIB"standard"
BODY_TYPE"PLUMBING"
HDL_TAP"TRUE";
"B \NAC \NWC"14;
"S \NAC"
BN"0"172;
%"TAP"
"1","(-1750,3400)","2","standard","I43";
;
CDS_LIB"standard"
BODY_TYPE"PLUMBING"
HDL_TAP"TRUE";
"B \NAC \NWC"14;
"S \NAC"
BN"4"164;
%"TAP"
"1","(-1750,3350)","2","standard","I44";
;
CDS_LIB"standard"
BODY_TYPE"PLUMBING"
HDL_TAP"TRUE";
"B \NAC \NWC"14;
"S \NAC"
BN"3"166;
%"TAP"
"1","(-1750,3500)","2","standard","I45";
;
CDS_LIB"standard"
BODY_TYPE"PLUMBING"
HDL_TAP"TRUE";
"B \NAC \NWC"14;
"S \NAC"
BN"6"160;
%"TAP"
"1","(-1750,3450)","2","standard","I46";
;
CDS_LIB"standard"
BODY_TYPE"PLUMBING"
HDL_TAP"TRUE";
"B \NAC \NWC"14;
"S \NAC"
BN"5"162;
%"TAP"
"1","(-1750,3650)","2","standard","I47";
;
CDS_LIB"standard"
BODY_TYPE"PLUMBING"
HDL_TAP"TRUE";
"B \NAC \NWC"13;
"S \NAC"
BN"1"171;
%"TAP"
"1","(-1750,3600)","2","standard","I48";
;
CDS_LIB"standard"
BODY_TYPE"PLUMBING"
HDL_TAP"TRUE";
"B \NAC \NWC"13;
"S \NAC"
BN"0"173;
%"TAP"
"1","(-100,700)","0","standard","I49";
;
CDS_LIB"standard"
BODY_TYPE"PLUMBING"
HDL_TAP"TRUE";
"B \NAC \NWC"15;
"S \NAC"
BN"0"94;
%"TAP"
"1","(-100,750)","0","standard","I50";
;
CDS_LIB"standard"
BODY_TYPE"PLUMBING"
HDL_TAP"TRUE";
"B \NAC \NWC"15;
"S \NAC"
BN"1"95;
%"TAP"
"1","(-100,850)","0","standard","I51";
;
CDS_LIB"standard"
BODY_TYPE"PLUMBING"
HDL_TAP"TRUE";
"B \NAC \NWC"15;
"S \NAC"
BN"3"96;
%"TAP"
"1","(-100,800)","0","standard","I52";
;
CDS_LIB"standard"
BODY_TYPE"PLUMBING"
HDL_TAP"TRUE";
"B \NAC \NWC"15;
"S \NAC"
BN"2"20;
%"TAP"
"1","(-100,1000)","0","standard","I53";
;
CDS_LIB"standard"
BODY_TYPE"PLUMBING"
HDL_TAP"TRUE";
"B \NAC \NWC"15;
"S \NAC"
BN"6"99;
%"TAP"
"1","(-100,950)","0","standard","I54";
;
CDS_LIB"standard"
BODY_TYPE"PLUMBING"
HDL_TAP"TRUE";
"B \NAC \NWC"15;
"S \NAC"
BN"5"98;
%"TAP"
"1","(-100,900)","0","standard","I55";
;
CDS_LIB"standard"
BODY_TYPE"PLUMBING"
HDL_TAP"TRUE";
"B \NAC \NWC"15;
"S \NAC"
BN"4"97;
%"TAP"
"1","(-100,1050)","0","standard","I56";
;
CDS_LIB"standard"
BODY_TYPE"PLUMBING"
HDL_TAP"TRUE";
"B \NAC \NWC"15;
"S \NAC"
BN"7"100;
%"TAP"
"1","(-100,1100)","0","standard","I57";
;
CDS_LIB"standard"
BODY_TYPE"PLUMBING"
HDL_TAP"TRUE";
"B \NAC \NWC"15;
"S \NAC"
BN"8"101;
%"TAP"
"1","(-100,1150)","0","standard","I58";
;
CDS_LIB"standard"
BODY_TYPE"PLUMBING"
HDL_TAP"TRUE";
"B \NAC \NWC"15;
"S \NAC"
BN"9"102;
%"TAP"
"1","(-100,1200)","0","standard","I59";
;
CDS_LIB"standard"
BODY_TYPE"PLUMBING"
HDL_TAP"TRUE";
"B \NAC \NWC"15;
"S \NAC"
BN"10"103;
%"TAP"
"1","(-100,1250)","0","standard","I60";
;
CDS_LIB"standard"
BODY_TYPE"PLUMBING"
HDL_TAP"TRUE";
"B \NAC \NWC"15;
"S \NAC"
BN"11"104;
%"TAP"
"1","(-100,1300)","0","standard","I61";
;
CDS_LIB"standard"
BODY_TYPE"PLUMBING"
HDL_TAP"TRUE";
"B \NAC \NWC"15;
"S \NAC"
BN"12"105;
%"TAP"
"1","(-100,1350)","0","standard","I62";
;
CDS_LIB"standard"
BODY_TYPE"PLUMBING"
HDL_TAP"TRUE";
"B \NAC \NWC"15;
"S \NAC"
BN"13"106;
%"TAP"
"1","(-100,1400)","0","standard","I63";
;
CDS_LIB"standard"
BODY_TYPE"PLUMBING"
HDL_TAP"TRUE";
"B \NAC \NWC"15;
"S \NAC"
BN"14"107;
%"TAP"
"1","(-100,1450)","0","standard","I64";
;
CDS_LIB"standard"
BODY_TYPE"PLUMBING"
HDL_TAP"TRUE";
"B \NAC \NWC"15;
"S \NAC"
BN"15"108;
%"TAP"
"1","(-100,1500)","0","standard","I65";
;
CDS_LIB"standard"
BODY_TYPE"PLUMBING"
HDL_TAP"TRUE";
"B \NAC \NWC"15;
"S \NAC"
BN"16"109;
%"TAP"
"1","(-100,1550)","0","standard","I66";
;
CDS_LIB"standard"
BODY_TYPE"PLUMBING"
HDL_TAP"TRUE";
"B \NAC \NWC"15;
"S \NAC"
BN"17"110;
%"TAP"
"1","(-100,1600)","0","standard","I67";
;
CDS_LIB"standard"
BODY_TYPE"PLUMBING"
HDL_TAP"TRUE";
"B \NAC \NWC"15;
"S \NAC"
BN"18"111;
%"TAP"
"1","(-100,1650)","0","standard","I68";
;
CDS_LIB"standard"
BODY_TYPE"PLUMBING"
HDL_TAP"TRUE";
"B \NAC \NWC"15;
"S \NAC"
BN"19"112;
%"TAP"
"1","(-100,1750)","0","standard","I69";
;
CDS_LIB"standard"
BODY_TYPE"PLUMBING"
HDL_TAP"TRUE";
"B \NAC \NWC"15;
"S \NAC"
BN"21"114;
%"TAP"
"1","(-100,1700)","0","standard","I70";
;
CDS_LIB"standard"
BODY_TYPE"PLUMBING"
HDL_TAP"TRUE";
"B \NAC \NWC"15;
"S \NAC"
BN"20"113;
%"TAP"
"1","(-100,1850)","0","standard","I71";
;
CDS_LIB"standard"
BODY_TYPE"PLUMBING"
HDL_TAP"TRUE";
"B \NAC \NWC"15;
"S \NAC"
BN"23"116;
%"TAP"
"1","(-100,1900)","0","standard","I72";
;
CDS_LIB"standard"
BODY_TYPE"PLUMBING"
HDL_TAP"TRUE";
"B \NAC \NWC"15;
"S \NAC"
BN"24"117;
%"TAP"
"1","(-100,1800)","0","standard","I73";
;
CDS_LIB"standard"
BODY_TYPE"PLUMBING"
HDL_TAP"TRUE";
"B \NAC \NWC"15;
"S \NAC"
BN"22"115;
%"TAP"
"1","(-100,1950)","0","standard","I74";
;
CDS_LIB"standard"
BODY_TYPE"PLUMBING"
HDL_TAP"TRUE";
"B \NAC \NWC"15;
"S \NAC"
BN"25"118;
%"TAP"
"1","(-100,2000)","0","standard","I75";
;
CDS_LIB"standard"
BODY_TYPE"PLUMBING"
HDL_TAP"TRUE";
"B \NAC \NWC"15;
"S \NAC"
BN"26"119;
%"TAP"
"1","(-100,2050)","0","standard","I76";
;
CDS_LIB"standard"
BODY_TYPE"PLUMBING"
HDL_TAP"TRUE";
"B \NAC \NWC"15;
"S \NAC"
BN"27"120;
%"TAP"
"1","(-100,2100)","0","standard","I77";
;
CDS_LIB"standard"
BODY_TYPE"PLUMBING"
HDL_TAP"TRUE";
"B \NAC \NWC"15;
"S \NAC"
BN"28"121;
%"TAP"
"1","(-100,2150)","0","standard","I78";
;
CDS_LIB"standard"
BODY_TYPE"PLUMBING"
HDL_TAP"TRUE";
"B \NAC \NWC"15;
"S \NAC"
BN"29"122;
%"TAP"
"1","(-100,2250)","0","standard","I79";
;
CDS_LIB"standard"
BODY_TYPE"PLUMBING"
HDL_TAP"TRUE";
"B \NAC \NWC"15;
"S \NAC"
BN"31"124;
%"TAP"
"1","(-100,2200)","0","standard","I80";
;
CDS_LIB"standard"
BODY_TYPE"PLUMBING"
HDL_TAP"TRUE";
"B \NAC \NWC"15;
"S \NAC"
BN"30"123;
%"TAP"
"1","(-100,2350)","0","standard","I81";
;
CDS_LIB"standard"
BODY_TYPE"PLUMBING"
HDL_TAP"TRUE";
"B \NAC \NWC"10;
"S \NAC"
BN"0"72;
%"TAP"
"1","(-100,2400)","0","standard","I82";
;
CDS_LIB"standard"
BODY_TYPE"PLUMBING"
HDL_TAP"TRUE";
"B \NAC \NWC"10;
"S \NAC"
BN"1"125;
%"TAP"
"1","(-100,2450)","0","standard","I83";
;
CDS_LIB"standard"
BODY_TYPE"PLUMBING"
HDL_TAP"TRUE";
"B \NAC \NWC"10;
"S \NAC"
BN"2"77;
%"TAP"
"1","(-100,2500)","0","standard","I84";
;
CDS_LIB"standard"
BODY_TYPE"PLUMBING"
HDL_TAP"TRUE";
"B \NAC \NWC"10;
"S \NAC"
BN"3"76;
%"TAP"
"1","(-100,2550)","0","standard","I85";
;
CDS_LIB"standard"
BODY_TYPE"PLUMBING"
HDL_TAP"TRUE";
"B \NAC \NWC"10;
"S \NAC"
BN"4"126;
%"TAP"
"1","(-100,2600)","0","standard","I86";
;
CDS_LIB"standard"
BODY_TYPE"PLUMBING"
HDL_TAP"TRUE";
"B \NAC \NWC"10;
"S \NAC"
BN"5"127;
%"TAP"
"1","(-100,2650)","0","standard","I87";
;
CDS_LIB"standard"
BODY_TYPE"PLUMBING"
HDL_TAP"TRUE";
"B \NAC \NWC"10;
"S \NAC"
BN"6"128;
%"TAP"
"1","(-100,2750)","0","standard","I88";
;
CDS_LIB"standard"
BODY_TYPE"PLUMBING"
HDL_TAP"TRUE";
"B \NAC \NWC"10;
"S \NAC"
BN"8"129;
%"TAP"
"1","(-100,2700)","0","standard","I89";
;
CDS_LIB"standard"
BODY_TYPE"PLUMBING"
HDL_TAP"TRUE";
"B \NAC \NWC"10;
"S \NAC"
BN"7"82;
%"TAP"
"1","(-100,2800)","0","standard","I90";
;
CDS_LIB"standard"
BODY_TYPE"PLUMBING"
HDL_TAP"TRUE";
"B \NAC \NWC"10;
"S \NAC"
BN"9"130;
%"TAP"
"1","(-100,2900)","0","standard","I91";
;
CDS_LIB"standard"
BODY_TYPE"PLUMBING"
HDL_TAP"TRUE";
"B \NAC \NWC"10;
"S \NAC"
BN"11"132;
%"TAP"
"1","(-100,2850)","0","standard","I92";
;
CDS_LIB"standard"
BODY_TYPE"PLUMBING"
HDL_TAP"TRUE";
"B \NAC \NWC"10;
"S \NAC"
BN"10"131;
%"TAP"
"1","(-100,3000)","0","standard","I93";
;
CDS_LIB"standard"
BODY_TYPE"PLUMBING"
HDL_TAP"TRUE";
"B \NAC \NWC"10;
"S \NAC"
BN"13"134;
%"TAP"
"1","(-100,3050)","0","standard","I94";
;
CDS_LIB"standard"
BODY_TYPE"PLUMBING"
HDL_TAP"TRUE";
"B \NAC \NWC"10;
"S \NAC"
BN"14"135;
%"TAP"
"1","(-100,2950)","0","standard","I95";
;
CDS_LIB"standard"
BODY_TYPE"PLUMBING"
HDL_TAP"TRUE";
"B \NAC \NWC"10;
"S \NAC"
BN"12"133;
%"TAP"
"1","(-100,3150)","0","standard","I96";
;
CDS_LIB"standard"
BODY_TYPE"PLUMBING"
HDL_TAP"TRUE";
"B \NAC \NWC"10;
"S \NAC"
BN"16"137;
%"TAP"
"1","(-100,3100)","0","standard","I97";
;
CDS_LIB"standard"
BODY_TYPE"PLUMBING"
HDL_TAP"TRUE";
"B \NAC \NWC"10;
"S \NAC"
BN"15"136;
%"TAP"
"1","(-100,3300)","0","standard","I98";
;
CDS_LIB"standard"
BODY_TYPE"PLUMBING"
HDL_TAP"TRUE";
"B \NAC \NWC"10;
"S \NAC"
BN"19"140;
%"TAP"
"1","(-100,3250)","0","standard","I99";
;
CDS_LIB"standard"
BODY_TYPE"PLUMBING"
HDL_TAP"TRUE";
"B \NAC \NWC"10;
"S \NAC"
BN"18"139;
END.
